FILE_TYPE = CONNECTIVITY;
{Allegro Design Entry HDL 17.2-2016 S081 (4005846) 1/11/2022}
"PAGE_NUMBER" = 263;
0"NC";
END.
